FILE_TYPE = CONNECTIVITY;
{Allegro Design Entry HDL 17.2-2016 S081 (4005846) 1/11/2022}
"PAGE_NUMBER" = 79;
0"NC";
1"PVCCFA_EHV_FIVRA_CPU1\g";
2"PVCCINFAON_CPU1\g";
3"PVCCFA_EHV_CPU1\g";
4"PVCCD_HV_CPU1\g";
5"PVCCIN_CPU1\g";
6"PVNN_MAIN_CPU1\g";
7"GND\g";
8"GND\g";
9"GND\g";
10"GND\g";
11"GND\g";
12"GND\g";
%"Q_CAP"
"1","(-4425,-2375)","0","pure_quanta","I1";
;
PART_NUMBER"CH647KMEA04"
VOLTAGE"4V"
TOLERANCE"20%"
PACK_TYPE"C0805"
MATERIAL"X6S"
VALUE"47UF"
$LOCATION"C450"
CDS_LIB"pure_quanta"
CDS_LOCATION"C450"
$SEC"1"
CDS_SEC"1";
"B"
$PN"2"9;
"A"
$PN"1"1;
%"Q_CAP"
"1","(-3075,-1400)","0","pure_quanta","I10";
;
PART_NUMBER"CH647KMEA04"
VOLTAGE"4V"
TOLERANCE"20%"
PACK_TYPE"C0805"
MATERIAL"X6S"
VALUE"47UF"
$LOCATION"C487"
CDS_LIB"pure_quanta"
CDS_LOCATION"C487"
$SEC"1"
CDS_SEC"1";
"B"
$PN"2"7;
"A"
$PN"1"2;
%"Q_CAP"
"1","(-3525,-1400)","0","pure_quanta","I11";
;
PART_NUMBER"CH647KMEA04"
VOLTAGE"4V"
TOLERANCE"20%"
PACK_TYPE"C0805"
VALUE"47UF"
MATERIAL"X6S"
$LOCATION"C486"
CDS_LIB"pure_quanta"
CDS_LOCATION"C486"
$SEC"1"
CDS_SEC"1";
"B"
$PN"2"7;
"A"
$PN"1"2;
%"Q_CAP"
"1","(-3975,-1400)","0","pure_quanta","I12";
;
PART_NUMBER"CH647KMEA04"
TOLERANCE"20%"
VOLTAGE"4V"
PACK_TYPE"C0805"
MATERIAL"X6S"
VALUE"47UF"
$LOCATION"C484"
CDS_LIB"pure_quanta"
CDS_LOCATION"C484"
$SEC"1"
CDS_SEC"1";
"B"
$PN"2"7;
"A"
$PN"1"2;
%"Q_CAP"
"1","(-4425,-1400)","0","pure_quanta","I13";
;
PART_NUMBER"CH647KMEA04"
VOLTAGE"4V"
TOLERANCE"20%"
PACK_TYPE"C0805"
MATERIAL"X6S"
VALUE"47UF"
$LOCATION"C481"
CDS_LIB"pure_quanta"
CDS_LOCATION"C481"
$SEC"1"
CDS_SEC"1";
"B"
$PN"2"7;
"A"
$PN"1"2;
%"UNIVERSAL_POWER"
"1","(-4425,-1125)","0","logical_power","I14";
;
HDL_POWER"PVCCINFAON_CPU1"
CDS_LIB"logical_power";
"A"2;
%"Q_CAP"
"1","(-4425,-400)","0","pure_quanta","I15";
;
PART_NUMBER"CH647KMEA04"
TOLERANCE"20%"
VOLTAGE"4V"
PACK_TYPE"C0805"
MATERIAL"X6S"
VALUE"47UF"
$LOCATION"C456"
CDS_LIB"pure_quanta"
CDS_LOCATION"C456"
$SEC"1"
CDS_SEC"1";
"B"
$PN"2"12;
"A"
$PN"1"3;
%"Q_CAP"
"1","(-3975,-400)","0","pure_quanta","I16";
;
PART_NUMBER"CH647KMEA04"
VOLTAGE"4V"
TOLERANCE"20%"
PACK_TYPE"C0805"
VALUE"47UF"
MATERIAL"X6S"
$LOCATION"C460"
CDS_LIB"pure_quanta"
CDS_LOCATION"C460"
$SEC"1"
CDS_SEC"1";
"B"
$PN"2"12;
"A"
$PN"1"3;
%"Q_CAP"
"1","(-3525,-400)","0","pure_quanta","I17";
;
PART_NUMBER"CH647KMEA04"
VOLTAGE"4V"
TOLERANCE"20%"
PACK_TYPE"C0805"
MATERIAL"X6S"
VALUE"47UF"
$LOCATION"C464"
CDS_LIB"pure_quanta"
CDS_LOCATION"C464"
$SEC"1"
CDS_SEC"1";
"B"
$PN"2"12;
"A"
$PN"1"3;
%"UNIVERSAL_POWER"
"1","(-4425,-125)","0","logical_power","I18";
;
HDL_POWER"PVCCFA_EHV_CPU1"
CDS_LIB"logical_power";
"A"3;
%"Q_CAP"
"1","(-4400,1475)","0","pure_quanta","I19";
;
PART_NUMBER"CH647KMEA04"
VOLTAGE"4V"
TOLERANCE"20%"
PACK_TYPE"C0805"
MATERIAL"X6S"
VALUE"47UF"
$LOCATION"C455"
CDS_LIB"pure_quanta"
CDS_LOCATION"C455"
$SEC"1"
CDS_SEC"1";
"B"
$PN"2"8;
"A"
$PN"1"4;
%"UNIVERSAL_POWER"
"1","(-4425,-2100)","0","logical_power","I2";
;
HDL_POWER"PVCCFA_EHV_FIVRA_CPU1"
CDS_LIB"logical_power";
"A"1;
%"Q_CAP"
"1","(-3950,1475)","0","pure_quanta","I20";
;
PART_NUMBER"CH647KMEA04"
VOLTAGE"4V"
TOLERANCE"20%"
PACK_TYPE"C0805"
MATERIAL"X6S"
VALUE"47UF"
$LOCATION"C459"
CDS_LIB"pure_quanta"
CDS_LOCATION"C459"
$SEC"1"
CDS_SEC"1";
"B"
$PN"2"8;
"A"
$PN"1"4;
%"Q_CAP"
"1","(-3500,1475)","0","pure_quanta","I21";
;
PART_NUMBER"CH647KMEA04"
VOLTAGE"4V"
TOLERANCE"20%"
PACK_TYPE"C0805"
MATERIAL"X6S"
VALUE"47UF"
$LOCATION"C463"
CDS_LIB"pure_quanta"
CDS_LOCATION"C463"
$SEC"1"
CDS_SEC"1";
"B"
$PN"2"8;
"A"
$PN"1"4;
%"UNIVERSAL_POWER"
"1","(-4400,1750)","0","logical_power","I22";
;
HDL_POWER"PVCCD_HV_CPU1"
CDS_LIB"logical_power";
"A"4;
%"Q_CAP"
"1","(-4400,2400)","0","pure_quanta","I23";
;
PART_NUMBER"CH647KMEA04"
VOLTAGE"4V"
TOLERANCE"20%"
PACK_TYPE"C0805"
MATERIAL"X6S"
VALUE"47UF"
$LOCATION"C342"
CDS_LIB"pure_quanta"
$LOCATION"C342"
CDS_LOCATION"C342"
$SEC"1"
CDS_SEC"1";
"B"
$PN"2"11;
"A"
$PN"1"5;
%"Q_CAP"
"1","(-3950,2400)","0","pure_quanta","I24";
;
PART_NUMBER"CH647KMEA04"
VOLTAGE"4V"
TOLERANCE"20%"
PACK_TYPE"C0805"
MATERIAL"X6S"
VALUE"47UF"
$LOCATION"C344"
CDS_LIB"pure_quanta"
$LOCATION"C344"
CDS_LOCATION"C344"
$SEC"1"
CDS_SEC"1";
"B"
$PN"2"11;
"A"
$PN"1"5;
%"Q_CAP"
"1","(-3500,2400)","0","pure_quanta","I25";
;
PART_NUMBER"CH647KMEA04"
VOLTAGE"4V"
TOLERANCE"20%"
PACK_TYPE"C0805"
MATERIAL"X6S"
VALUE"47UF"
$LOCATION"C346"
CDS_LIB"pure_quanta"
$LOCATION"C346"
CDS_LOCATION"C346"
$SEC"1"
CDS_SEC"1";
"B"
$PN"2"11;
"A"
$PN"1"5;
%"Q_CAP"
"1","(-3075,-400)","0","pure_quanta","I26";
;
PART_NUMBER"CH647KMEA04"
PACK_TYPE"C0805"
VOLTAGE"4V"
MATERIAL"X6S"
TOLERANCE"20%"
VALUE"47UF"
$LOCATION"C468"
CDS_LIB"pure_quanta"
CDS_LOCATION"C468"
$SEC"1"
CDS_SEC"1";
"B"
$PN"2"12;
"A"
$PN"1"3;
%"Q_CAP"
"1","(-2625,-400)","0","pure_quanta","I27";
;
PART_NUMBER"CH647LME900"
VALUE"47UF"
VOLTAGE"2.5V"
TOLERANCE"20%"
PACK_TYPE"C0603"
MATERIAL"X6S"
$LOCATION"C472"
CDS_LIB"pure_quanta"
CDS_LOCATION"C472"
$SEC"1"
CDS_SEC"1";
"B"
$PN"2"12;
"A"
$PN"1"3;
%"UNIVERSAL_GND"
"1","(-2175,-750)","0","logical_power","I28";
;
CDS_LIB"logical_power"
HDL_POWER"GND";
"A"12;
%"Q_CAP"
"1","(-2175,-400)","0","pure_quanta","I29";
;
PART_NUMBER"CH647LME900"
VOLTAGE"2.5V"
VALUE"47UF"
TOLERANCE"20%"
PACK_TYPE"C0603"
MATERIAL"X6S"
$LOCATION"C475"
CDS_LIB"pure_quanta"
CDS_LOCATION"C475"
$SEC"1"
CDS_SEC"1";
"B"
$PN"2"12;
"A"
$PN"1"3;
%"Q_CAP"
"1","(-3975,-2375)","0","pure_quanta","I3";
;
PART_NUMBER"CH647KMEA04"
VOLTAGE"4V"
TOLERANCE"20%"
PACK_TYPE"C0805"
MATERIAL"X6S"
VALUE"47UF"
$LOCATION"C454"
CDS_LIB"pure_quanta"
CDS_LOCATION"C454"
$SEC"1"
CDS_SEC"1";
"B"
$PN"2"9;
"A"
$PN"1"1;
%"UNIVERSAL_GND"
"1","(-3050,1150)","0","logical_power","I30";
;
CDS_LIB"logical_power"
HDL_POWER"GND";
"A"8;
%"Q_CAP"
"1","(-3050,1475)","0","pure_quanta","I31";
;
PART_NUMBER"CH647KMEA04"
VOLTAGE"4V"
TOLERANCE"20%"
PACK_TYPE"C0805"
MATERIAL"X6S"
VALUE"47UF"
$LOCATION"C467"
CDS_LIB"pure_quanta"
CDS_LOCATION"C467"
$SEC"1"
CDS_SEC"1";
"B"
$PN"2"8;
"A"
$PN"1"4;
%"Q_CAP"
"1","(-3050,2400)","0","pure_quanta","I32";
;
PART_NUMBER"CH647KMEA04"
VOLTAGE"4V"
TOLERANCE"20%"
PACK_TYPE"C0805"
MATERIAL"X6S"
VALUE"47UF"
$LOCATION"C348"
CDS_LIB"pure_quanta"
$LOCATION"C348"
CDS_LOCATION"C348"
$SEC"1"
CDS_SEC"1";
"B"
$PN"2"11;
"A"
$PN"1"5;
%"Q_CAP"
"1","(-2600,2400)","0","pure_quanta","I33";
;
PART_NUMBER"CH647KMEA04"
VOLTAGE"4V"
TOLERANCE"20%"
PACK_TYPE"C0805"
MATERIAL"X6S"
VALUE"47UF"
$LOCATION"C350"
CDS_LIB"pure_quanta"
$LOCATION"C350"
CDS_LOCATION"C350"
$SEC"1"
CDS_SEC"1";
"B"
$PN"2"11;
"A"
$PN"1"5;
%"Q_CAP"
"1","(-2150,2400)","0","pure_quanta","I34";
;
PART_NUMBER"CH647KMEA04"
VOLTAGE"4V"
TOLERANCE"20%"
PACK_TYPE"C0805"
MATERIAL"X6S"
VALUE"47UF"
$LOCATION"C352"
CDS_LIB"pure_quanta"
$LOCATION"C352"
CDS_LOCATION"C352"
$SEC"1"
CDS_SEC"1";
"B"
$PN"2"11;
"A"
$PN"1"5;
%"Q_CAP"
"1","(-1700,2400)","0","pure_quanta","I35";
;
PART_NUMBER"CH647KMEA04"
VOLTAGE"4V"
TOLERANCE"20%"
PACK_TYPE"C0805"
MATERIAL"X6S"
VALUE"47UF"
$LOCATION"C354"
CDS_LIB"pure_quanta"
$LOCATION"C354"
CDS_LOCATION"C354"
$SEC"1"
CDS_SEC"1";
"B"
$PN"2"11;
"A"
$PN"1"5;
%"UNIVERSAL_POWER"
"1","(-4400,2675)","0","logical_power","I36";
;
HDL_POWER"PVCCIN_CPU1"
CDS_LIB"logical_power";
"A"5;
%"Q_CAP"
"1","(-1275,-2375)","0","pure_quanta","I37";
;
PART_NUMBER"CH647KMEA04"
VOLTAGE"4V"
TOLERANCE"20%"
PACK_TYPE"C0805"
MATERIAL"X6S"
VALUE"47UF"
$LOCATION"C476"
CDS_LIB"pure_quanta"
CDS_LOCATION"C476"
$SEC"1"
CDS_SEC"1";
"B"
$PN"2"9;
"A"
$PN"1"1;
%"Q_CAP"
"1","(-825,-2375)","0","pure_quanta","I38";
;
PART_NUMBER"CH647KMEA04"
VOLTAGE"4V"
TOLERANCE"20%"
PACK_TYPE"C0805"
MATERIAL"X6S"
VALUE"47UF"
$LOCATION"C477"
CDS_LIB"pure_quanta"
CDS_LOCATION"C477"
$SEC"1"
CDS_SEC"1";
"B"
$PN"2"9;
"A"
$PN"1"1;
%"Q_CAP"
"1","(-375,-2375)","0","pure_quanta","I39";
;
PART_NUMBER"CH647KMEA04"
VOLTAGE"4V"
TOLERANCE"20%"
PACK_TYPE"C0805"
MATERIAL"X6S"
VALUE"47UF"
$LOCATION"C479"
CDS_LIB"pure_quanta"
CDS_LOCATION"C479"
$SEC"1"
CDS_SEC"1";
"B"
$PN"2"9;
"A"
$PN"1"1;
%"Q_CAP"
"1","(-3525,-2375)","0","pure_quanta","I4";
;
PART_NUMBER"CH647KMEA04"
VOLTAGE"4V"
TOLERANCE"20%"
PACK_TYPE"C0805"
VALUE"47UF"
MATERIAL"X6S"
$LOCATION"C458"
CDS_LIB"pure_quanta"
CDS_LOCATION"C458"
$SEC"1"
CDS_SEC"1";
"B"
$PN"2"9;
"A"
$PN"1"1;
%"UNIVERSAL_GND"
"1","(525,-2725)","0","logical_power","I40";
;
CDS_LIB"logical_power"
HDL_POWER"GND";
"A"9;
%"Q_CAP"
"1","(75,-2375)","0","pure_quanta","I41";
;
PART_NUMBER"CH647KMEA04"
VOLTAGE"4V"
TOLERANCE"20%"
PACK_TYPE"C0805"
MATERIAL"X6S"
VALUE"47UF"
$LOCATION"C482"
CDS_LIB"pure_quanta"
CDS_LOCATION"C482"
$SEC"1"
CDS_SEC"1";
"B"
$PN"2"9;
"A"
$PN"1"1;
%"Q_CAP"
"1","(525,-2375)","0","pure_quanta","I42";
;
PART_NUMBER"CH647KMEA04"
VOLTAGE"4V"
TOLERANCE"20%"
PACK_TYPE"C0805"
MATERIAL"X6S"
VALUE"47UF"
$LOCATION"C485"
CDS_LIB"pure_quanta"
CDS_LOCATION"C485"
$SEC"1"
CDS_SEC"1";
"B"
$PN"2"9;
"A"
$PN"1"1;
%"Q_CAP"
"1","(-1175,1450)","0","pure_quanta","I43";
;
PART_NUMBER"CH647KMEA04"
VOLTAGE"4V"
MATERIAL"X6S"
TOLERANCE"20%"
VALUE"47UF"
PACK_TYPE"C0805"
$LOCATION"C1403"
CDS_LIB"pure_quanta"
CDS_LOCATION"C1403"
$SEC"1"
CDS_SEC"1";
"B"
$PN"2"10;
"A"
$PN"1"6;
%"Q_CAP"
"1","(-725,1450)","0","pure_quanta","I44";
;
PART_NUMBER"CH647KMEA04"
VOLTAGE"4V"
MATERIAL"X6S"
TOLERANCE"20%"
VALUE"47UF"
PACK_TYPE"C0805"
$LOCATION"C1404"
CDS_LIB"pure_quanta"
CDS_LOCATION"C1404"
$SEC"1"
CDS_SEC"1";
"B"
$PN"2"10;
"A"
$PN"1"6;
%"UNIVERSAL_POWER"
"1","(-1175,1725)","0","logical_power","I45";
;
HDL_POWER"PVNN_MAIN_CPU1"
CDS_LIB"logical_power";
"A"6;
%"Q_CAP"
"1","(-1250,2400)","0","pure_quanta","I46";
;
PART_NUMBER"CH647KMEA04"
VOLTAGE"4V"
TOLERANCE"20%"
PACK_TYPE"C0805"
MATERIAL"X6S"
VALUE"47UF"
$LOCATION"C322"
CDS_LIB"pure_quanta"
$LOCATION"C322"
CDS_LOCATION"C322"
$SEC"1"
CDS_SEC"1";
"B"
$PN"2"11;
"A"
$PN"1"5;
%"Q_CAP"
"1","(-800,2400)","0","pure_quanta","I47";
;
PART_NUMBER"CH647KMEA04"
VOLTAGE"4V"
TOLERANCE"20%"
PACK_TYPE"C0805"
MATERIAL"X6S"
VALUE"47UF"
$LOCATION"C325"
CDS_LIB"pure_quanta"
$LOCATION"C325"
CDS_LOCATION"C325"
$SEC"1"
CDS_SEC"1";
"B"
$PN"2"11;
"A"
$PN"1"5;
%"UNIVERSAL_GND"
"1","(-325,1100)","0","logical_power","I48";
;
CDS_LIB"logical_power"
HDL_POWER"GND";
"A"10;
%"Q_CAP"
"1","(-325,1450)","0","pure_quanta","I49";
;
PART_NUMBER"CH622KMEB01"
PACK_TYPE"C0402"
VALUE"22UF"
VOLTAGE"4V"
MATERIAL"X6S"
TOLERANCE"20%"
$LOCATION"C1353"
CDS_LIB"pure_quanta"
CDS_LOCATION"C1353"
$SEC"1"
CDS_SEC"1";
"B"
$PN"2"10;
"A"
$PN"1"6;
%"Q_CAP"
"1","(-3075,-2375)","0","pure_quanta","I5";
;
PART_NUMBER"CH647KMEA04"
VOLTAGE"4V"
TOLERANCE"20%"
PACK_TYPE"C0805"
MATERIAL"X6S"
VALUE"47UF"
$LOCATION"C462"
CDS_LIB"pure_quanta"
CDS_LOCATION"C462"
$SEC"1"
CDS_SEC"1";
"B"
$PN"2"9;
"A"
$PN"1"1;
%"Q_CAP"
"1","(-350,2400)","0","pure_quanta","I50";
;
PART_NUMBER"CH647KMEA04"
VOLTAGE"4V"
TOLERANCE"20%"
PACK_TYPE"C0805"
MATERIAL"X6S"
VALUE"47UF"
$LOCATION"C328"
CDS_LIB"pure_quanta"
$LOCATION"C328"
CDS_LOCATION"C328"
$SEC"1"
CDS_SEC"1";
"B"
$PN"2"11;
"A"
$PN"1"5;
%"Q_CAP"
"1","(100,2400)","0","pure_quanta","I51";
;
PART_NUMBER"CH647KMEA04"
VOLTAGE"4V"
TOLERANCE"20%"
PACK_TYPE"C0805"
MATERIAL"X6S"
VALUE"47UF"
$LOCATION"C341"
CDS_LIB"pure_quanta"
$LOCATION"C341"
CDS_LOCATION"C341"
$SEC"1"
CDS_SEC"1";
"B"
$PN"2"11;
"A"
$PN"1"5;
%"Q_CAP"
"1","(550,2400)","0","pure_quanta","I52";
;
PART_NUMBER"CH647KMEA04"
VOLTAGE"4V"
TOLERANCE"20%"
PACK_TYPE"C0805"
MATERIAL"X6S"
VALUE"47UF"
$LOCATION"C343"
CDS_LIB"pure_quanta"
$LOCATION"C343"
CDS_LOCATION"C343"
$SEC"1"
CDS_SEC"1";
"B"
$PN"2"11;
"A"
$PN"1"5;
%"Q_CAP"
"1","(1000,2400)","0","pure_quanta","I53";
;
PART_NUMBER"CH647KMEA04"
VOLTAGE"4V"
TOLERANCE"20%"
PACK_TYPE"C0805"
MATERIAL"X6S"
VALUE"47UF"
$LOCATION"C345"
CDS_LIB"pure_quanta"
$LOCATION"C345"
CDS_LOCATION"C345"
$SEC"1"
CDS_SEC"1";
"B"
$PN"2"11;
"A"
$PN"1"5;
%"UNIVERSAL_GND"
"1","(1450,2075)","0","logical_power","I54";
;
CDS_LIB"logical_power"
HDL_POWER"GND";
"A"11;
%"Q_CAP"
"1","(1450,2400)","0","pure_quanta","I55";
;
PART_NUMBER"CH647KMEA04"
VOLTAGE"4V"
TOLERANCE"20%"
PACK_TYPE"C0805"
MATERIAL"X6S"
VALUE"47UF"
$LOCATION"C347"
CDS_LIB"pure_quanta"
$LOCATION"C347"
CDS_LOCATION"C347"
$SEC"1"
CDS_SEC"1";
"B"
$PN"2"11;
"A"
$PN"1"5;
%"UNIVERSAL_GND"
"1","(-3075,-1750)","0","logical_power","I6";
;
CDS_LIB"logical_power"
HDL_POWER"GND";
"A"7;
%"Q_CAP"
"1","(-2625,-2375)","0","pure_quanta","I7";
;
PART_NUMBER"CH647KMEA04"
VOLTAGE"4V"
TOLERANCE"20%"
PACK_TYPE"C0805"
MATERIAL"X6S"
VALUE"47UF"
$LOCATION"C466"
CDS_LIB"pure_quanta"
CDS_LOCATION"C466"
$SEC"1"
CDS_SEC"1";
"B"
$PN"2"9;
"A"
$PN"1"1;
%"Q_CAP"
"1","(-2175,-2375)","0","pure_quanta","I8";
;
PART_NUMBER"CH647KMEA04"
VOLTAGE"4V"
TOLERANCE"20%"
PACK_TYPE"C0805"
MATERIAL"X6S"
VALUE"47UF"
$LOCATION"C470"
CDS_LIB"pure_quanta"
CDS_LOCATION"C470"
$SEC"1"
CDS_SEC"1";
"B"
$PN"2"9;
"A"
$PN"1"1;
%"Q_CAP"
"1","(-1725,-2375)","0","pure_quanta","I9";
;
PART_NUMBER"CH647KMEA04"
VOLTAGE"4V"
TOLERANCE"20%"
PACK_TYPE"C0805"
MATERIAL"X6S"
VALUE"47UF"
$LOCATION"C473"
CDS_LIB"pure_quanta"
CDS_LOCATION"C473"
$SEC"1"
CDS_SEC"1";
"B"
$PN"2"9;
"A"
$PN"1"1;
END.
